(kicad_pcb
	(version 20260206)
	(generator "pcbnew")
	(generator_version "10.0")
	(general
		(thickness 1.6)
		(legacy_teardrops no)
	)
	(paper "A4")
	(title_block
		(title "Bryce Canyon_IOM_IOC_16318-2_OCP.brd")
		(comment 1 "Bryce Canyon / footprints 123-129 of 1605")
	)
	(layers
		(0 "F.Cu" signal "TOP")
		(4 "In1.Cu" signal "L2GND")
		(6 "In2.Cu" signal "L3")
		(8 "In3.Cu" signal "L4VCC")
		(10 "In4.Cu" signal "L5VCC")
		(12 "In5.Cu" signal "L6")
		(14 "In6.Cu" signal "L7GND")
		(2 "B.Cu" signal "BOTTOM")
		(9 "F.Adhes" user "F.Adhesive")
		(11 "B.Adhes" user "B.Adhesive")
		(13 "F.Paste" user "Package Geometry/Pastemask Top")
		(15 "B.Paste" user "Package Geometry/Pastemask Bottom")
		(5 "F.SilkS" user "Ref Des/Silkscreen Top")
		(7 "B.SilkS" user "Ref Des/Silkscreen Bottom")
		(1 "F.Mask" user "Board Geometry/Soldermask Top")
		(3 "B.Mask" user "Board Geometry/Soldermask Bottom")
		(17 "Dwgs.User" user "User.Drawings")
		(19 "Cmts.User" user "User.Comments")
		(21 "Eco1.User" user "User.Eco1")
		(23 "Eco2.User" user "User.Eco2")
		(25 "Edge.Cuts" user "Board Geometry/Outline")
		(27 "Margin" user)
		(31 "F.CrtYd" user "Package Geometry/Place Bound Top")
		(29 "B.CrtYd" user "Package Geometry/Place Bound Bottom")
		(35 "F.Fab" user "Ref Des/Assembly Top")
		(33 "B.Fab" user "Ref Des/Assembly Bottom")
	)
	(footprint ""
		(layer "F.Cu")
		(at 179.832 -115.443)
		(property "Reference" "C288"
			(at 0 0 0)
			(layer "F.SilkS")
			(hide yes)
			(effects
				(font
					(size 1.27 1.27)
				)
			)
		)
		(property "Value" "SCD1U50V3KX-GP"
			(at 0 -2.8194 0)
			(unlocked yes)
			(layer "F.Fab")
			(hide yes)
			(effects
				(font
					(size 1.016 1.016)
					(thickness 0.1524)
				)
			)
		)
		(property "Device Type" "C603H36"
			(at 0 -4.3434 0)
			(unlocked yes)
			(layer "F.Fab")
			(hide yes)
			(effects
				(font
					(size 1.016 1.016)
					(thickness 0.1524)
				)
			)
		)
		(duplicate_pad_numbers_are_jumpers no)
		(fp_line
			(start 0.508 0)
			(end -0.508 0)
			(stroke
				(width 0.2032)
				(type default)
			)
			(layer "F.SilkS")
		)
		(fp_rect
			(start -0.5842 1.3335)
			(end 0.5842 -1.3335)
			(stroke
				(width 0)
				(type default)
			)
			(fill no)
			(layer "F.CrtYd")
		)
		(fp_rect
			(start -0.5842 1.3335)
			(end 0.5842 -1.3335)
			(stroke
				(width 0)
				(type default)
			)
			(fill no)
			(layer "F.Fab")
		)
		(pad "1" smd custom
			(at 0 -0.762)
			(size 0.2159 0.2159)
			(layers "F.Cu" "F.Mask" "F.Paste")
			(net "P3V3_STBY")
			(options
				(clearance outline)
				(anchor circle)
			)
			(primitives
				(gr_poly
					(pts
						(arc
							(start -0.3302 -0.4318)
							(mid -0.402042 -0.402042)
							(end -0.4318 -0.3302)
						)
						(arc
							(start -0.4318 0.3302)
							(mid -0.402042 0.402042)
							(end -0.3302 0.4318)
						)
						(arc
							(start 0.3302 0.4318)
							(mid 0.402042 0.402042)
							(end 0.4318 0.3302)
						)
						(arc
							(start 0.4318 -0.3302)
							(mid 0.402042 -0.402042)
							(end 0.3302 -0.4318)
						)
					)
					(width 0)
					(fill yes)
				)
			)
		)
		(pad "2" smd custom
			(at 0 0.762)
			(size 0.2159 0.2159)
			(layers "F.Cu" "F.Mask" "F.Paste")
			(net "GND")
			(options
				(clearance outline)
				(anchor circle)
			)
			(primitives
				(gr_poly
					(pts
						(arc
							(start -0.3302 -0.4318)
							(mid -0.402042 -0.402042)
							(end -0.4318 -0.3302)
						)
						(arc
							(start -0.4318 0.3302)
							(mid -0.402042 0.402042)
							(end -0.3302 0.4318)
						)
						(arc
							(start 0.3302 0.4318)
							(mid 0.402042 0.402042)
							(end 0.4318 0.3302)
						)
						(arc
							(start 0.4318 -0.3302)
							(mid 0.402042 -0.402042)
							(end 0.3302 -0.4318)
						)
					)
					(width 0)
					(fill yes)
				)
			)
		)
	)
	(footprint ""
		(layer "F.Cu")
		(at 201.698352 -129.644648 180)
		(property "Reference" "C257"
			(at 0 0 180)
			(layer "F.SilkS")
			(hide yes)
			(effects
				(font
					(size 1.27 1.27)
				)
			)
		)
		(property "Value" "SCD1U16V2KX-3GP"
			(at 1.1811 -2.7051 180)
			(unlocked yes)
			(layer "F.Fab")
			(hide yes)
			(effects
				(font
					(size 1.016 1.016)
					(thickness 0.1524)
				)
			)
		)
		(property "Device Type" "C402H22"
			(at 1.1811 -4.2291 180)
			(unlocked yes)
			(layer "F.Fab")
			(hide yes)
			(effects
				(font
					(size 1.016 1.016)
					(thickness 0.1524)
				)
			)
		)
		(duplicate_pad_numbers_are_jumpers no)
		(fp_rect
			(start -0.4318 0.9525)
			(end 0.4318 -0.9525)
			(stroke
				(width 0)
				(type default)
			)
			(fill no)
			(layer "F.CrtYd")
		)
		(fp_rect
			(start -0.4318 0.9525)
			(end 0.4318 -0.9525)
			(stroke
				(width 0)
				(type default)
			)
			(fill no)
			(layer "F.Fab")
		)
		(pad "1" smd custom
			(at 0 -0.4445 180)
			(size 0.1524 0.1524)
			(layers "F.Cu" "F.Mask" "F.Paste")
			(net "TPS74801_1V5_EN")
			(options
				(clearance outline)
				(anchor circle)
			)
			(primitives
				(gr_poly
					(pts
						(arc
							(start 0.3048 -0.2032)
							(mid 0.275042 -0.275042)
							(end 0.2032 -0.3048)
						)
						(arc
							(start -0.2032 -0.3048)
							(mid -0.275042 -0.275042)
							(end -0.3048 -0.2032)
						)
						(arc
							(start -0.3048 0.2032)
							(mid -0.275042 0.275042)
							(end -0.2032 0.3048)
						)
						(arc
							(start 0.2032 0.3048)
							(mid 0.275042 0.275042)
							(end 0.3048 0.2032)
						)
					)
					(width 0)
					(fill yes)
				)
			)
		)
		(pad "2" smd custom
			(at 0 0.4445 180)
			(size 0.1524 0.1524)
			(layers "F.Cu" "F.Mask" "F.Paste")
			(net "GND")
			(options
				(clearance outline)
				(anchor circle)
			)
			(primitives
				(gr_poly
					(pts
						(arc
							(start 0.3048 -0.2032)
							(mid 0.275042 -0.275042)
							(end 0.2032 -0.3048)
						)
						(arc
							(start -0.2032 -0.3048)
							(mid -0.275042 -0.275042)
							(end -0.3048 -0.2032)
						)
						(arc
							(start -0.3048 0.2032)
							(mid -0.275042 0.275042)
							(end -0.2032 0.3048)
						)
						(arc
							(start 0.2032 0.3048)
							(mid 0.275042 0.275042)
							(end 0.3048 0.2032)
						)
					)
					(width 0)
					(fill yes)
				)
			)
		)
	)
	(footprint ""
		(layer "F.Cu")
		(at 119.384064 -13.65123 90)
		(property "Reference" "C133"
			(at 0 0 90)
			(layer "F.SilkS")
			(hide yes)
			(effects
				(font
					(size 1.27 1.27)
				)
			)
		)
		(property "Value" "SCD015U25V2KX-GP"
			(at 1.1811 -2.7051 90)
			(unlocked yes)
			(layer "F.Fab")
			(hide yes)
			(effects
				(font
					(size 1.016 1.016)
					(thickness 0.1524)
				)
			)
		)
		(property "Device Type" "C402H22"
			(at 1.1811 -4.2291 90)
			(unlocked yes)
			(layer "F.Fab")
			(hide yes)
			(effects
				(font
					(size 1.016 1.016)
					(thickness 0.1524)
				)
			)
		)
		(duplicate_pad_numbers_are_jumpers no)
		(fp_rect
			(start -0.4318 0.9525)
			(end 0.4318 -0.9525)
			(stroke
				(width 0)
				(type default)
			)
			(fill no)
			(layer "F.CrtYd")
		)
		(fp_rect
			(start -0.4318 0.9525)
			(end 0.4318 -0.9525)
			(stroke
				(width 0)
				(type default)
			)
			(fill no)
			(layer "F.Fab")
		)
		(pad "1" smd custom
			(at 0 -0.4445 90)
			(size 0.1524 0.1524)
			(layers "F.Cu" "F.Mask" "F.Paste")
			(net "MB0_CM_SENSE_P")
			(options
				(clearance outline)
				(anchor circle)
			)
			(primitives
				(gr_poly
					(pts
						(arc
							(start 0.3048 -0.2032)
							(mid 0.275042 -0.275042)
							(end 0.2032 -0.3048)
						)
						(arc
							(start -0.2032 -0.3048)
							(mid -0.275042 -0.275042)
							(end -0.3048 -0.2032)
						)
						(arc
							(start -0.3048 0.2032)
							(mid -0.275042 0.275042)
							(end -0.2032 0.3048)
						)
						(arc
							(start 0.2032 0.3048)
							(mid 0.275042 0.275042)
							(end 0.3048 0.2032)
						)
					)
					(width 0)
					(fill yes)
				)
			)
		)
		(pad "2" smd custom
			(at 0 0.4445 90)
			(size 0.1524 0.1524)
			(layers "F.Cu" "F.Mask" "F.Paste")
			(net "MB0_CM_SENSE_N")
			(options
				(clearance outline)
				(anchor circle)
			)
			(primitives
				(gr_poly
					(pts
						(arc
							(start 0.3048 -0.2032)
							(mid 0.275042 -0.275042)
							(end 0.2032 -0.3048)
						)
						(arc
							(start -0.2032 -0.3048)
							(mid -0.275042 -0.275042)
							(end -0.3048 -0.2032)
						)
						(arc
							(start -0.3048 0.2032)
							(mid -0.275042 0.275042)
							(end -0.2032 0.3048)
						)
						(arc
							(start 0.2032 0.3048)
							(mid 0.275042 0.275042)
							(end 0.3048 0.2032)
						)
					)
					(width 0)
					(fill yes)
				)
			)
		)
	)
	(footprint ""
		(layer "F.Cu")
		(at 23.777956 -128.105408 180)
		(property "Reference" "LED6"
			(at 0 0 180)
			(layer "F.SilkS")
			(hide yes)
			(effects
				(font
					(size 1.27 1.27)
				)
			)
		)
		(property "Value" "LED-YG-51-GP"
			(at -2.6924 -1.4224 180)
			(unlocked yes)
			(layer "F.Fab")
			(hide yes)
			(effects
				(font
					(size 1.016 1.016)
					(thickness 0.1524)
				)
			)
		)
		(property "Device Type" "LED1608AKH40"
			(at -2.6924 -2.9464 180)
			(unlocked yes)
			(layer "F.Fab")
			(hide yes)
			(effects
				(font
					(size 1.016 1.016)
					(thickness 0.1524)
				)
			)
		)
		(duplicate_pad_numbers_are_jumpers no)
		(fp_line
			(start 0.7493 1.651)
			(end 0.7493 1.1811)
			(stroke
				(width 0.3302)
				(type default)
			)
			(layer "F.SilkS")
		)
		(fp_line
			(start 0.6604 1.3716)
			(end -0.6604 1.3716)
			(stroke
				(width 0.1524)
				(type default)
			)
			(layer "F.SilkS")
		)
		(fp_line
			(start 0.6604 -1.3716)
			(end 0.6604 1.3716)
			(stroke
				(width 0.1524)
				(type default)
			)
			(layer "F.SilkS")
		)
		(fp_line
			(start -0.5969 1.5494)
			(end 0.5842 1.5494)
			(stroke
				(width 0.508)
				(type default)
			)
			(layer "F.SilkS")
		)
		(fp_line
			(start -0.6604 1.3716)
			(end -0.6604 -1.3716)
			(stroke
				(width 0.1524)
				(type default)
			)
			(layer "F.SilkS")
		)
		(fp_line
			(start -0.6604 -1.3716)
			(end 0.6604 -1.3716)
			(stroke
				(width 0.1524)
				(type default)
			)
			(layer "F.SilkS")
		)
		(fp_line
			(start -0.7493 1.651)
			(end -0.7493 1.1811)
			(stroke
				(width 0.3302)
				(type default)
			)
			(layer "F.SilkS")
		)
		(fp_rect
			(start -0.6223 1.3335)
			(end 0.6223 -1.3335)
			(stroke
				(width 0)
				(type default)
			)
			(fill no)
			(layer "F.CrtYd")
		)
		(fp_rect
			(start -0.6223 1.3335)
			(end 0.6223 -1.3335)
			(stroke
				(width 0)
				(type default)
			)
			(fill no)
			(layer "F.Fab")
		)
		(pad "A" smd custom
			(at 0 -0.762 180)
			(size 0.2159 0.2159)
			(layers "F.Cu" "F.Mask" "F.Paste")
			(net "BMC_HBLED_R")
			(options
				(clearance outline)
				(anchor circle)
			)
			(primitives
				(gr_poly
					(pts
						(arc
							(start -0.3302 -0.4318)
							(mid -0.402042 -0.402042)
							(end -0.4318 -0.3302)
						)
						(arc
							(start -0.4318 0.3302)
							(mid -0.402042 0.402042)
							(end -0.3302 0.4318)
						)
						(arc
							(start 0.3302 0.4318)
							(mid 0.402042 0.402042)
							(end 0.4318 0.3302)
						)
						(arc
							(start 0.4318 -0.3302)
							(mid 0.402042 -0.402042)
							(end 0.3302 -0.4318)
						)
					)
					(width 0)
					(fill yes)
				)
			)
		)
		(pad "K" smd custom
			(at 0 0.762 180)
			(size 0.2159 0.2159)
			(layers "F.Cu" "F.Mask" "F.Paste")
			(net "BMC_HBLED")
			(options
				(clearance outline)
				(anchor circle)
			)
			(primitives
				(gr_poly
					(pts
						(arc
							(start -0.3302 -0.4318)
							(mid -0.402042 -0.402042)
							(end -0.4318 -0.3302)
						)
						(arc
							(start -0.4318 0.3302)
							(mid -0.402042 0.402042)
							(end -0.3302 0.4318)
						)
						(arc
							(start 0.3302 0.4318)
							(mid 0.402042 0.402042)
							(end 0.4318 0.3302)
						)
						(arc
							(start 0.4318 -0.3302)
							(mid 0.402042 -0.402042)
							(end 0.3302 -0.4318)
						)
					)
					(width 0)
					(fill yes)
				)
			)
		)
	)
	(footprint ""
		(layer "F.Cu")
		(at 160.533588 -96.416114 -90)
		(property "Reference" "R597"
			(at 0 0 270)
			(layer "F.SilkS")
			(hide yes)
			(effects
				(font
					(size 1.27 1.27)
				)
			)
		)
		(property "Value" "0R2J-2-GP"
			(at 0.064008 -3.993896 270)
			(unlocked yes)
			(layer "F.Fab")
			(hide yes)
			(effects
				(font
					(size 1.016 1.016)
					(thickness 0.1524)
				)
			)
		)
		(property "Device Type" "R402H16"
			(at 0.064008 -5.517896 270)
			(unlocked yes)
			(layer "F.Fab")
			(hide yes)
			(effects
				(font
					(size 1.016 1.016)
					(thickness 0.1524)
				)
			)
		)
		(duplicate_pad_numbers_are_jumpers no)
		(fp_line
			(start -0.508 -0.9398)
			(end -0.508 0.9398)
			(stroke
				(width 0.1524)
				(type default)
			)
			(layer "F.SilkS")
		)
		(fp_line
			(start 0.508 -0.9398)
			(end -0.508 -0.9398)
			(stroke
				(width 0.1524)
				(type default)
			)
			(layer "F.SilkS")
		)
		(fp_rect
			(start -0.508 0.9398)
			(end 0.508 -0.9398)
			(stroke
				(width 0)
				(type default)
			)
			(fill no)
			(layer "F.CrtYd")
		)
		(fp_rect
			(start -0.508 0.9398)
			(end 0.508 -0.9398)
			(stroke
				(width 0)
				(type default)
			)
			(fill no)
			(layer "F.Fab")
		)
		(pad "1" smd custom
			(at 0 -0.4445 270)
			(size 0.1397 0.1397)
			(layers "F.Cu" "F.Mask" "F.Paste")
			(net "IOM_FULL_PGOOD")
			(options
				(clearance outline)
				(anchor circle)
			)
			(primitives
				(gr_poly
					(pts
						(arc
							(start -0.1778 -0.2794)
							(mid -0.249642 -0.249642)
							(end -0.2794 -0.1778)
						)
						(arc
							(start -0.2794 0.1778)
							(mid -0.249642 0.249642)
							(end -0.1778 0.2794)
						)
						(arc
							(start 0.1778 0.2794)
							(mid 0.249642 0.249642)
							(end 0.2794 0.1778)
						)
						(arc
							(start 0.2794 -0.1778)
							(mid 0.249642 -0.249642)
							(end 0.1778 -0.2794)
						)
					)
					(width 0)
					(fill yes)
				)
			)
		)
		(pad "2" smd custom
			(at 0 0.4445 270)
			(size 0.1397 0.1397)
			(layers "F.Cu" "F.Mask" "F.Paste")
			(net "U43_VREF2")
			(options
				(clearance outline)
				(anchor circle)
			)
			(primitives
				(gr_poly
					(pts
						(arc
							(start -0.1778 -0.2794)
							(mid -0.249642 -0.249642)
							(end -0.2794 -0.1778)
						)
						(arc
							(start -0.2794 0.1778)
							(mid -0.249642 0.249642)
							(end -0.1778 0.2794)
						)
						(arc
							(start 0.1778 0.2794)
							(mid 0.249642 0.249642)
							(end 0.2794 0.1778)
						)
						(arc
							(start 0.2794 -0.1778)
							(mid 0.249642 -0.249642)
							(end 0.1778 -0.2794)
						)
					)
					(width 0)
					(fill yes)
				)
			)
		)
	)
	(footprint ""
		(layer "F.Cu")
		(at 10.791698 -141.008862 90)
		(property "Reference" "R228"
			(at 0 0 90)
			(layer "F.SilkS")
			(hide yes)
			(effects
				(font
					(size 1.27 1.27)
				)
			)
		)
		(property "Value" "120R2F-GP"
			(at 0.064008 -3.993896 90)
			(unlocked yes)
			(layer "F.Fab")
			(hide yes)
			(effects
				(font
					(size 1.016 1.016)
					(thickness 0.1524)
				)
			)
		)
		(property "Device Type" "R402H16"
			(at 0.064008 -5.517896 90)
			(unlocked yes)
			(layer "F.Fab")
			(hide yes)
			(effects
				(font
					(size 1.016 1.016)
					(thickness 0.1524)
				)
			)
		)
		(duplicate_pad_numbers_are_jumpers no)
		(fp_line
			(start 0.508 -0.9398)
			(end -0.508 -0.9398)
			(stroke
				(width 0.1524)
				(type default)
			)
			(layer "F.SilkS")
		)
		(fp_line
			(start -0.508 -0.9398)
			(end -0.508 0.9398)
			(stroke
				(width 0.1524)
				(type default)
			)
			(layer "F.SilkS")
		)
		(fp_rect
			(start -0.508 0.9398)
			(end 0.508 -0.9398)
			(stroke
				(width 0)
				(type default)
			)
			(fill no)
			(layer "F.CrtYd")
		)
		(fp_rect
			(start -0.508 0.9398)
			(end 0.508 -0.9398)
			(stroke
				(width 0)
				(type default)
			)
			(fill no)
			(layer "F.Fab")
		)
		(pad "1" smd custom
			(at 0 -0.4445 90)
			(size 0.1397 0.1397)
			(layers "F.Cu" "F.Mask" "F.Paste")
			(net "MEMWEN")
			(options
				(clearance outline)
				(anchor circle)
			)
			(primitives
				(gr_poly
					(pts
						(arc
							(start -0.1778 -0.2794)
							(mid -0.249642 -0.249642)
							(end -0.2794 -0.1778)
						)
						(arc
							(start -0.2794 0.1778)
							(mid -0.249642 0.249642)
							(end -0.1778 0.2794)
						)
						(arc
							(start 0.1778 0.2794)
							(mid 0.249642 0.249642)
							(end 0.2794 0.1778)
						)
						(arc
							(start 0.2794 -0.1778)
							(mid 0.249642 -0.249642)
							(end 0.1778 -0.2794)
						)
					)
					(width 0)
					(fill yes)
				)
			)
		)
		(pad "2" smd custom
			(at 0 0.4445 90)
			(size 0.1397 0.1397)
			(layers "F.Cu" "F.Mask" "F.Paste")
			(net "P1V2_STBY")
			(options
				(clearance outline)
				(anchor circle)
			)
			(primitives
				(gr_poly
					(pts
						(arc
							(start -0.1778 -0.2794)
							(mid -0.249642 -0.249642)
							(end -0.2794 -0.1778)
						)
						(arc
							(start -0.2794 0.1778)
							(mid -0.249642 0.249642)
							(end -0.1778 0.2794)
						)
						(arc
							(start 0.1778 0.2794)
							(mid 0.249642 0.249642)
							(end 0.2794 0.1778)
						)
						(arc
							(start 0.2794 -0.1778)
							(mid 0.249642 -0.249642)
							(end 0.1778 -0.2794)
						)
					)
					(width 0)
					(fill yes)
				)
			)
		)
	)
	(footprint ""
		(layer "F.Cu")
		(at 52.8066 -162.4838 180)
		(property "Reference" "C122"
			(at 0 0 180)
			(layer "F.SilkS")
			(hide yes)
			(effects
				(font
					(size 1.27 1.27)
				)
			)
		)
		(property "Value" "SCD1U25V2KX-2-GP"
			(at 1.1811 -2.7051 180)
			(unlocked yes)
			(layer "F.Fab")
			(hide yes)
			(effects
				(font
					(size 1.016 1.016)
					(thickness 0.1524)
				)
			)
		)
		(property "Device Type" "C402H22"
			(at 1.1811 -4.2291 180)
			(unlocked yes)
			(layer "F.Fab")
			(hide yes)
			(effects
				(font
					(size 1.016 1.016)
					(thickness 0.1524)
				)
			)
		)
		(duplicate_pad_numbers_are_jumpers no)
		(fp_rect
			(start -0.4318 0.9525)
			(end 0.4318 -0.9525)
			(stroke
				(width 0)
				(type default)
			)
			(fill no)
			(layer "F.CrtYd")
		)
		(fp_rect
			(start -0.4318 0.9525)
			(end 0.4318 -0.9525)
			(stroke
				(width 0)
				(type default)
			)
			(fill no)
			(layer "F.Fab")
		)
		(pad "1" smd custom
			(at 0 -0.4445 180)
			(size 0.1524 0.1524)
			(layers "F.Cu" "F.Mask" "F.Paste")
			(net "ADC_P3V3")
			(options
				(clearance outline)
				(anchor circle)
			)
			(primitives
				(gr_poly
					(pts
						(arc
							(start 0.3048 -0.2032)
							(mid 0.275042 -0.275042)
							(end 0.2032 -0.3048)
						)
						(arc
							(start -0.2032 -0.3048)
							(mid -0.275042 -0.275042)
							(end -0.3048 -0.2032)
						)
						(arc
							(start -0.3048 0.2032)
							(mid -0.275042 0.275042)
							(end -0.2032 0.3048)
						)
						(arc
							(start 0.2032 0.3048)
							(mid 0.275042 0.275042)
							(end 0.3048 0.2032)
						)
					)
					(width 0)
					(fill yes)
				)
			)
		)
		(pad "2" smd custom
			(at 0 0.4445 180)
			(size 0.1524 0.1524)
			(layers "F.Cu" "F.Mask" "F.Paste")
			(net "GND")
			(options
				(clearance outline)
				(anchor circle)
			)
			(primitives
				(gr_poly
					(pts
						(arc
							(start 0.3048 -0.2032)
							(mid 0.275042 -0.275042)
							(end 0.2032 -0.3048)
						)
						(arc
							(start -0.2032 -0.3048)
							(mid -0.275042 -0.275042)
							(end -0.3048 -0.2032)
						)
						(arc
							(start -0.3048 0.2032)
							(mid -0.275042 0.275042)
							(end -0.2032 0.3048)
						)
						(arc
							(start 0.2032 0.3048)
							(mid 0.275042 0.275042)
							(end 0.3048 0.2032)
						)
					)
					(width 0)
					(fill yes)
				)
			)
		)
	)
)
